(kicad_pcb
	(version 20260206)
	(generator "pcbnew")
	(generator_version "10.0")
	(general
		(thickness 1.6)
		(legacy_teardrops no)
	)
	(paper "A4")
	(title_block
		(title "01162023_DA0F0TEBIF0_F0T_Expander_BD_F_brd_V02_OCP.brd")
		(comment 1 "Grand Teton / footprints 1515-1521 of 9728")
	)
	(layers
		(0 "F.Cu" signal "TOP")
		(4 "In1.Cu" signal "GND")
		(6 "In2.Cu" signal "VCC")
		(8 "In3.Cu" signal "VCC1")
		(10 "In4.Cu" signal "GND1")
		(12 "In5.Cu" signal "IN1")
		(14 "In6.Cu" signal "GND2")
		(16 "In7.Cu" signal "IN2")
		(18 "In8.Cu" signal "GND3")
		(20 "In9.Cu" signal "IN3")
		(22 "In10.Cu" signal "GND4")
		(24 "In11.Cu" signal "IN4")
		(26 "In12.Cu" signal "GND5")
		(28 "In13.Cu" signal "IN5")
		(30 "In14.Cu" signal "GND6")
		(32 "In15.Cu" signal "IN6")
		(34 "In16.Cu" signal "GND7")
		(2 "B.Cu" signal "BOTTOM")
		(9 "F.Adhes" user "F.Adhesive")
		(11 "B.Adhes" user "B.Adhesive")
		(13 "F.Paste" user "Package Geometry/Pastemask Top")
		(15 "B.Paste" user "Package Geometry/Pastemask Bottom")
		(5 "F.SilkS" user "Ref Des/Silkscreen Top")
		(7 "B.SilkS" user "Ref Des/Silkscreen Bottom")
		(1 "F.Mask" user "Board Geometry/Soldermask Top")
		(3 "B.Mask" user "Board Geometry/Soldermask Bottom")
		(17 "Dwgs.User" user "User.Drawings")
		(19 "Cmts.User" user "User.Comments")
		(21 "Eco1.User" user "User.Eco1")
		(23 "Eco2.User" user "User.Eco2")
		(25 "Edge.Cuts" user "Board Geometry/Outline")
		(27 "Margin" user)
		(31 "F.CrtYd" user "Package Geometry/Place Bound Top")
		(29 "B.CrtYd" user "Package Geometry/Place Bound Bottom")
		(35 "F.Fab" user "Ref Des/Assembly Top")
		(33 "B.Fab" user "Ref Des/Assembly Bottom")
	)
	(footprint ""
		(layer "F.Cu")
		(at 247.817386 -258.04495 -90)
		(property "Reference" "R6534"
			(at 0 0 270)
			(layer "F.SilkS")
			(hide yes)
			(effects
				(font
					(size 1.27 1.27)
				)
			)
		)
		(property "Value" ""
			(at 0 0 270)
			(layer "F.Fab")
			(effects
				(font
					(size 1.27 1.27)
				)
			)
		)
		(duplicate_pad_numbers_are_jumpers no)
		(fp_line
			(start -0.7874 0.4064)
			(end -0.7874 -0.4064)
			(stroke
				(width 0.1524)
				(type default)
			)
			(layer "F.SilkS")
		)
		(fp_line
			(start 0.7874 0.4064)
			(end -0.7874 0.4064)
			(stroke
				(width 0.1524)
				(type default)
			)
			(layer "F.SilkS")
		)
		(fp_line
			(start -0.7874 -0.4064)
			(end 0.7874 -0.4064)
			(stroke
				(width 0.1524)
				(type default)
			)
			(layer "F.SilkS")
		)
		(fp_line
			(start 0.7874 -0.4064)
			(end 0.7874 0.4064)
			(stroke
				(width 0.1524)
				(type default)
			)
			(layer "F.SilkS")
		)
		(fp_line
			(start -0.67945 0.3048)
			(end -0.67945 -0.305054)
			(stroke
				(width 0.1)
				(type default)
			)
			(layer "F.Fab")
		)
		(fp_line
			(start -0.12065 0.3048)
			(end -0.67945 0.3048)
			(stroke
				(width 0.1)
				(type default)
			)
			(layer "F.Fab")
		)
		(fp_line
			(start 0.120396 0.3048)
			(end 0.120396 0.2794)
			(stroke
				(width 0.1)
				(type default)
			)
			(layer "F.Fab")
		)
		(fp_line
			(start 0.67945 0.3048)
			(end 0.120396 0.3048)
			(stroke
				(width 0.1)
				(type default)
			)
			(layer "F.Fab")
		)
		(fp_line
			(start -0.12065 0.2794)
			(end -0.12065 0.3048)
			(stroke
				(width 0.1)
				(type default)
			)
			(layer "F.Fab")
		)
		(fp_line
			(start 0.120396 0.2794)
			(end -0.12065 0.2794)
			(stroke
				(width 0.1)
				(type default)
			)
			(layer "F.Fab")
		)
		(fp_line
			(start -0.12065 -0.2794)
			(end 0.12065 -0.2794)
			(stroke
				(width 0.1)
				(type default)
			)
			(layer "F.Fab")
		)
		(fp_line
			(start 0.12065 -0.2794)
			(end 0.12065 -0.3048)
			(stroke
				(width 0.1)
				(type default)
			)
			(layer "F.Fab")
		)
		(fp_line
			(start 0.12065 -0.3048)
			(end 0.67945 -0.3048)
			(stroke
				(width 0.1)
				(type default)
			)
			(layer "F.Fab")
		)
		(fp_line
			(start 0.67945 -0.3048)
			(end 0.67945 0.3048)
			(stroke
				(width 0.1)
				(type default)
			)
			(layer "F.Fab")
		)
		(fp_line
			(start -0.67945 -0.305054)
			(end -0.12065 -0.305054)
			(stroke
				(width 0.1)
				(type default)
			)
			(layer "F.Fab")
		)
		(fp_line
			(start -0.12065 -0.305054)
			(end -0.12065 -0.2794)
			(stroke
				(width 0.1)
				(type default)
			)
			(layer "F.Fab")
		)
		(pad "1" smd circle
			(at -0.40005 0 270)
			(size 0 0)
			(layers "F.Cu" "F.Mask" "F.Paste")
			(net "P1V25_SERDES_VDDPLL_PEX2")
		)
		(pad "2" smd circle
			(at 0.40005 0 270)
			(size 0 0)
			(layers "F.Cu" "F.Mask" "F.Paste")
			(net "P1V25_SERDES_VDDPLL_PEX2_C11")
		)
	)
	(footprint ""
		(layer "F.Cu")
		(at 147.494244 -29.507688 -90)
		(property "Reference" "PC923"
			(at 0 0 270)
			(layer "F.SilkS")
			(hide yes)
			(effects
				(font
					(size 1.27 1.27)
				)
			)
		)
		(property "Value" ""
			(at 0 0 270)
			(layer "F.Fab")
			(effects
				(font
					(size 1.27 1.27)
				)
			)
		)
		(duplicate_pad_numbers_are_jumpers no)
		(fp_line
			(start -1.524 0.762)
			(end -1.524 -0.762)
			(stroke
				(width 0.1524)
				(type default)
			)
			(layer "F.SilkS")
		)
		(fp_line
			(start 1.524 0.762)
			(end -1.524 0.762)
			(stroke
				(width 0.1524)
				(type default)
			)
			(layer "F.SilkS")
		)
		(fp_line
			(start -1.524 -0.762)
			(end 1.524 -0.762)
			(stroke
				(width 0.1524)
				(type default)
			)
			(layer "F.SilkS")
		)
		(fp_line
			(start 1.524 -0.762)
			(end 1.524 0.762)
			(stroke
				(width 0.1524)
				(type default)
			)
			(layer "F.SilkS")
		)
		(fp_line
			(start -1.1049 0.724916)
			(end 1.1049 0.724916)
			(stroke
				(width 0.1)
				(type default)
			)
			(layer "F.Fab")
		)
		(fp_line
			(start 1.1049 0.724916)
			(end 1.1049 -0.724916)
			(stroke
				(width 0.1)
				(type default)
			)
			(layer "F.Fab")
		)
		(fp_line
			(start -1.1049 -0.724916)
			(end -1.1049 0.724916)
			(stroke
				(width 0.1)
				(type default)
			)
			(layer "F.Fab")
		)
		(fp_line
			(start 1.1049 -0.724916)
			(end -1.1049 -0.724916)
			(stroke
				(width 0.1)
				(type default)
			)
			(layer "F.Fab")
		)
		(pad "1" smd rect
			(at -0.889 0 90)
			(size 1.016 1.27)
			(layers "F.Cu" "F.Mask" "F.Paste")
			(net "P3V3_SSD5")
		)
		(pad "2" smd rect
			(at 0.889 0 90)
			(size 1.016 1.27)
			(layers "F.Cu" "F.Mask" "F.Paste")
			(net "GND")
		)
	)
	(footprint ""
		(layer "F.Cu")
		(at 46.174914 -48.753014 180)
		(property "Reference" "C210"
			(at 0 0 180)
			(layer "F.SilkS")
			(hide yes)
			(effects
				(font
					(size 1.27 1.27)
				)
			)
		)
		(property "Value" ""
			(at 0 0 180)
			(layer "F.Fab")
			(effects
				(font
					(size 1.27 1.27)
				)
			)
		)
		(duplicate_pad_numbers_are_jumpers no)
		(fp_line
			(start 0.7874 0.4064)
			(end -0.7874 0.4064)
			(stroke
				(width 0.1524)
				(type default)
			)
			(layer "F.SilkS")
		)
		(fp_line
			(start 0.7874 -0.4064)
			(end 0.7874 0.4064)
			(stroke
				(width 0.1524)
				(type default)
			)
			(layer "F.SilkS")
		)
		(fp_line
			(start -0.7874 0.4064)
			(end -0.7874 -0.4064)
			(stroke
				(width 0.1524)
				(type default)
			)
			(layer "F.SilkS")
		)
		(fp_line
			(start -0.7874 -0.4064)
			(end 0.7874 -0.4064)
			(stroke
				(width 0.1524)
				(type default)
			)
			(layer "F.SilkS")
		)
		(fp_line
			(start 0.67945 0.3048)
			(end 0.120396 0.3048)
			(stroke
				(width 0.1)
				(type default)
			)
			(layer "F.Fab")
		)
		(fp_line
			(start 0.67945 -0.3048)
			(end 0.67945 0.3048)
			(stroke
				(width 0.1)
				(type default)
			)
			(layer "F.Fab")
		)
		(fp_line
			(start 0.12065 -0.2794)
			(end 0.12065 -0.3048)
			(stroke
				(width 0.1)
				(type default)
			)
			(layer "F.Fab")
		)
		(fp_line
			(start 0.12065 -0.3048)
			(end 0.67945 -0.3048)
			(stroke
				(width 0.1)
				(type default)
			)
			(layer "F.Fab")
		)
		(fp_line
			(start 0.120396 0.3048)
			(end 0.120396 0.2794)
			(stroke
				(width 0.1)
				(type default)
			)
			(layer "F.Fab")
		)
		(fp_line
			(start 0.120396 0.2794)
			(end -0.12065 0.2794)
			(stroke
				(width 0.1)
				(type default)
			)
			(layer "F.Fab")
		)
		(fp_line
			(start -0.12065 0.3048)
			(end -0.67945 0.3048)
			(stroke
				(width 0.1)
				(type default)
			)
			(layer "F.Fab")
		)
		(fp_line
			(start -0.12065 0.2794)
			(end -0.12065 0.3048)
			(stroke
				(width 0.1)
				(type default)
			)
			(layer "F.Fab")
		)
		(fp_line
			(start -0.12065 -0.2794)
			(end 0.12065 -0.2794)
			(stroke
				(width 0.1)
				(type default)
			)
			(layer "F.Fab")
		)
		(fp_line
			(start -0.12065 -0.305054)
			(end -0.12065 -0.2794)
			(stroke
				(width 0.1)
				(type default)
			)
			(layer "F.Fab")
		)
		(fp_line
			(start -0.67945 0.3048)
			(end -0.67945 -0.305054)
			(stroke
				(width 0.1)
				(type default)
			)
			(layer "F.Fab")
		)
		(fp_line
			(start -0.67945 -0.305054)
			(end -0.12065 -0.305054)
			(stroke
				(width 0.1)
				(type default)
			)
			(layer "F.Fab")
		)
		(pad "1" smd circle
			(at -0.40005 0 180)
			(size 0 0)
			(layers "F.Cu" "F.Mask" "F.Paste")
			(net "P3V3_AUX")
		)
		(pad "2" smd circle
			(at 0.40005 0 180)
			(size 0 0)
			(layers "F.Cu" "F.Mask" "F.Paste")
			(net "GND")
		)
	)
	(footprint ""
		(layer "F.Cu")
		(at 281.02052 -70.307454 90)
		(property "Reference" "PC869"
			(at 0 0 90)
			(layer "F.SilkS")
			(hide yes)
			(effects
				(font
					(size 1.27 1.27)
				)
			)
		)
		(property "Value" ""
			(at 0 0 90)
			(layer "F.Fab")
			(effects
				(font
					(size 1.27 1.27)
				)
			)
		)
		(duplicate_pad_numbers_are_jumpers no)
		(fp_line
			(start 0.7874 -0.4064)
			(end 0.7874 0.4064)
			(stroke
				(width 0.1524)
				(type default)
			)
			(layer "F.SilkS")
		)
		(fp_line
			(start -0.7874 -0.4064)
			(end 0.7874 -0.4064)
			(stroke
				(width 0.1524)
				(type default)
			)
			(layer "F.SilkS")
		)
		(fp_line
			(start 0.7874 0.4064)
			(end -0.7874 0.4064)
			(stroke
				(width 0.1524)
				(type default)
			)
			(layer "F.SilkS")
		)
		(fp_line
			(start -0.7874 0.4064)
			(end -0.7874 -0.4064)
			(stroke
				(width 0.1524)
				(type default)
			)
			(layer "F.SilkS")
		)
		(fp_line
			(start -0.12065 -0.305054)
			(end -0.12065 -0.2794)
			(stroke
				(width 0.1)
				(type default)
			)
			(layer "F.Fab")
		)
		(fp_line
			(start -0.67945 -0.305054)
			(end -0.12065 -0.305054)
			(stroke
				(width 0.1)
				(type default)
			)
			(layer "F.Fab")
		)
		(fp_line
			(start 0.67945 -0.3048)
			(end 0.67945 0.3048)
			(stroke
				(width 0.1)
				(type default)
			)
			(layer "F.Fab")
		)
		(fp_line
			(start 0.12065 -0.3048)
			(end 0.67945 -0.3048)
			(stroke
				(width 0.1)
				(type default)
			)
			(layer "F.Fab")
		)
		(fp_line
			(start 0.12065 -0.2794)
			(end 0.12065 -0.3048)
			(stroke
				(width 0.1)
				(type default)
			)
			(layer "F.Fab")
		)
		(fp_line
			(start -0.12065 -0.2794)
			(end 0.12065 -0.2794)
			(stroke
				(width 0.1)
				(type default)
			)
			(layer "F.Fab")
		)
		(fp_line
			(start 0.120396 0.2794)
			(end -0.12065 0.2794)
			(stroke
				(width 0.1)
				(type default)
			)
			(layer "F.Fab")
		)
		(fp_line
			(start -0.12065 0.2794)
			(end -0.12065 0.3048)
			(stroke
				(width 0.1)
				(type default)
			)
			(layer "F.Fab")
		)
		(fp_line
			(start 0.67945 0.3048)
			(end 0.120396 0.3048)
			(stroke
				(width 0.1)
				(type default)
			)
			(layer "F.Fab")
		)
		(fp_line
			(start 0.120396 0.3048)
			(end 0.120396 0.2794)
			(stroke
				(width 0.1)
				(type default)
			)
			(layer "F.Fab")
		)
		(fp_line
			(start -0.12065 0.3048)
			(end -0.67945 0.3048)
			(stroke
				(width 0.1)
				(type default)
			)
			(layer "F.Fab")
		)
		(fp_line
			(start -0.67945 0.3048)
			(end -0.67945 -0.305054)
			(stroke
				(width 0.1)
				(type default)
			)
			(layer "F.Fab")
		)
		(pad "1" smd circle
			(at -0.40005 0 90)
			(size 0 0)
			(layers "F.Cu" "F.Mask" "F.Paste")
			(net "P12V_AUX")
		)
		(pad "2" smd circle
			(at 0.40005 0 90)
			(size 0 0)
			(layers "F.Cu" "F.Mask" "F.Paste")
			(net "GND")
		)
	)
	(footprint ""
		(layer "F.Cu")
		(at 304.64633 -58.323734)
		(property "Reference" "PC427"
			(at 0 0 0)
			(layer "F.SilkS")
			(hide yes)
			(effects
				(font
					(size 1.27 1.27)
				)
			)
		)
		(property "Value" ""
			(at 0 0 0)
			(layer "F.Fab")
			(effects
				(font
					(size 1.27 1.27)
				)
			)
		)
		(duplicate_pad_numbers_are_jumpers no)
		(fp_line
			(start -1.524 -0.762)
			(end 1.524 -0.762)
			(stroke
				(width 0.1524)
				(type default)
			)
			(layer "F.SilkS")
		)
		(fp_line
			(start -1.524 0.762)
			(end -1.524 -0.762)
			(stroke
				(width 0.1524)
				(type default)
			)
			(layer "F.SilkS")
		)
		(fp_line
			(start 1.524 -0.762)
			(end 1.524 0.762)
			(stroke
				(width 0.1524)
				(type default)
			)
			(layer "F.SilkS")
		)
		(fp_line
			(start 1.524 0.762)
			(end -1.524 0.762)
			(stroke
				(width 0.1524)
				(type default)
			)
			(layer "F.SilkS")
		)
		(fp_line
			(start -1.1049 -0.724916)
			(end -1.1049 0.724916)
			(stroke
				(width 0.1)
				(type default)
			)
			(layer "F.Fab")
		)
		(fp_line
			(start -1.1049 0.724916)
			(end 1.1049 0.724916)
			(stroke
				(width 0.1)
				(type default)
			)
			(layer "F.Fab")
		)
		(fp_line
			(start 1.1049 -0.724916)
			(end -1.1049 -0.724916)
			(stroke
				(width 0.1)
				(type default)
			)
			(layer "F.Fab")
		)
		(fp_line
			(start 1.1049 0.724916)
			(end 1.1049 -0.724916)
			(stroke
				(width 0.1)
				(type default)
			)
			(layer "F.Fab")
		)
		(pad "1" smd rect
			(at -0.889 0 180)
			(size 1.016 1.27)
			(layers "F.Cu" "F.Mask" "F.Paste")
			(net "GND")
		)
		(pad "2" smd rect
			(at 0.889 0 180)
			(size 1.016 1.27)
			(layers "F.Cu" "F.Mask" "F.Paste")
			(net "P12V_AUX")
		)
	)
	(footprint ""
		(layer "F.Cu")
		(at 273.342608 -70.844918 -90)
		(property "Reference" "PD110"
			(at 4.093718 2.221738 90)
			(unlocked yes)
			(layer "F.SilkS")
			(effects
				(font
					(size 0.7874 0.5842)
					(thickness 0.1524)
				)
				(justify left)
			)
		)
		(property "Value" ""
			(at 0 0 270)
			(layer "F.Fab")
			(effects
				(font
					(size 1.27 1.27)
				)
			)
		)
		(duplicate_pad_numbers_are_jumpers no)
		(fp_line
			(start -3.400044 1.459992)
			(end -3.400044 -1.459992)
			(stroke
				(width 0.1524)
				(type default)
			)
			(layer "F.SilkS")
		)
		(fp_line
			(start 4.107942 1.459992)
			(end -3.400044 1.459992)
			(stroke
				(width 0.1524)
				(type default)
			)
			(layer "F.SilkS")
		)
		(fp_line
			(start -3.400044 -1.459992)
			(end 4.107942 -1.459992)
			(stroke
				(width 0.1524)
				(type default)
			)
			(layer "F.SilkS")
		)
		(fp_line
			(start 4.107942 -1.459992)
			(end 4.107942 1.459992)
			(stroke
				(width 0.1524)
				(type default)
			)
			(layer "F.SilkS")
		)
		(fp_poly
			(pts
				(xy 4.107942 -1.459992) (xy 4.107942 1.459992) (xy 3.308096 1.459992) (xy 3.308096 -1.459992)
			)
			(stroke
				(width 0)
				(type default)
			)
			(fill yes)
			(layer "F.SilkS")
		)
		(fp_line
			(start -2.29997 1.459992)
			(end -2.29997 -1.459992)
			(stroke
				(width 0.1)
				(type default)
			)
			(layer "F.Fab")
		)
		(fp_line
			(start 2.29997 1.459992)
			(end -2.29997 1.459992)
			(stroke
				(width 0.1)
				(type default)
			)
			(layer "F.Fab")
		)
		(fp_line
			(start -2.29997 -1.459992)
			(end 2.29997 -1.459992)
			(stroke
				(width 0.1)
				(type default)
			)
			(layer "F.Fab")
		)
		(fp_line
			(start 2.29997 -1.459992)
			(end 2.29997 1.459992)
			(stroke
				(width 0.1)
				(type default)
			)
			(layer "F.Fab")
		)
		(fp_text user "-"
			(at 5.4102 0.29845 90)
			(unlocked yes)
			(layer "F.SilkS")
			(effects
				(font
					(size 1.905 1.4224)
					(thickness 0.1524)
				)
				(justify left)
			)
		)
		(fp_text user "+"
			(at -5.093716 -1.278128 270)
			(unlocked yes)
			(layer "F.SilkS")
			(effects
				(font
					(size 1.905 1.4224)
					(thickness 0.1524)
				)
				(justify left)
			)
		)
		(fp_text user "-"
			(at 5.4102 0.29845 90)
			(unlocked yes)
			(layer "F.Fab")
			(effects
				(font
					(size 1.905 1.4224)
					(thickness 0.1524)
				)
				(justify left)
			)
		)
		(fp_text user "+"
			(at -4.7752 -0.12065 270)
			(unlocked yes)
			(layer "F.Fab")
			(effects
				(font
					(size 1.905 1.4224)
					(thickness 0.1524)
				)
				(justify left)
			)
		)
		(pad "A" smd rect
			(at -1.999996 0)
			(size 1.7018 2.5146)
			(layers "F.Cu" "F.Mask" "F.Paste")
			(net "GND")
		)
		(pad "C" smd rect
			(at 1.999996 0)
			(size 1.7018 2.5146)
			(layers "F.Cu" "F.Mask" "F.Paste")
			(net "P12V_SSD9_R")
		)
	)
	(footprint ""
		(layer "F.Cu")
		(at 284.330902 -343.952322 90)
		(property "Reference" "C600"
			(at 0 0 90)
			(layer "F.SilkS")
			(hide yes)
			(effects
				(font
					(size 1.27 1.27)
				)
			)
		)
		(property "Value" ""
			(at 0 0 90)
			(layer "F.Fab")
			(effects
				(font
					(size 1.27 1.27)
				)
			)
		)
		(duplicate_pad_numbers_are_jumpers no)
		(fp_line
			(start 0.299974 -0.150114)
			(end 0.299974 0.150114)
			(stroke
				(width 0.1)
				(type default)
			)
			(layer "F.Fab")
		)
		(fp_line
			(start -0.299974 -0.150114)
			(end 0.299974 -0.150114)
			(stroke
				(width 0.1)
				(type default)
			)
			(layer "F.Fab")
		)
		(fp_line
			(start 0.299974 0.150114)
			(end -0.299974 0.150114)
			(stroke
				(width 0.1)
				(type default)
			)
			(layer "F.Fab")
		)
		(fp_line
			(start -0.299974 0.150114)
			(end -0.299974 -0.150114)
			(stroke
				(width 0.1)
				(type default)
			)
			(layer "F.Fab")
		)
		(pad "1" smd rect
			(at -0.2667 0 90)
			(size 0.3048 0.381)
			(layers "F.Cu" "F.Mask" "F.Paste")
			(net "P5E_PEX2_STN7_TX_DN<119>")
		)
		(pad "2" smd rect
			(at 0.2667 0 90)
			(size 0.3048 0.381)
			(layers "F.Cu" "F.Mask" "F.Paste")
			(net "P5E_PEX2_STN7_TX_C_DN<119>")
		)
	)
)
